#ISCELL
  mstr_misc dns *
  *
#ISCELL
  mstr_symbols cad_note *
  *
#ISCELL
  mstr_symbols design_note *
  *
#ISCELL
  mstr_symbols intel_corp_bpage *
  *
#CELL
  mstr_ttl ttl1g126_a *
  page142_i1
#ISCELL
  mstr_standard offpage *
  page142_i11
#ISCELL
  mstr_standard offpage *
  page142_i12
#ISCELL
  mstr_standard offpage *
  page142_i13
#ISCELL
  mstr_standard offpage *
  page142_i17
#CELL
  mstr_discrete res *
  page142_i18
#ISCELL
  mstr_standard offpage *
  page142_i19
#CELL
  mstr_discrete res *
  page142_i2
#CELL
  dev_discrete cap_a *
  page142_i20
#ISCELL
  mstr_symbols p3v3_stby *
  page142_i21
#ISCELL
  mstr_symbols gnd *
  page142_i22
#ISCELL
  mstr_symbols p3v3_stby *
  page142_i24
#CELL
  mstr_discrete res *
  page142_i3
#CELL
  mstr_discrete res *
  page142_i30
#CELL
  mstr_discrete res *
  page142_i31
#CELL
  mstr_discrete res *
  page142_i32
#CELL
  mstr_discrete res *
  page142_i33
#CELL
  w_hdl 2k15r2f-1-gp *
  page142_i34
#CELL
  w_hdl 2k15r2f-1-gp *
  page142_i35
#ISCELL
  mstr_symbols p3v3_stby *
  page142_i4
#ISCELL
  mstr_standard offpage *
  page142_i5
